(kicad_pcb
	(version 20260206)
	(generator "pcbnew")
	(generator_version "10.0")
	(general
		(thickness 1.21888)
		(legacy_teardrops no)
	)
	(paper "A4")
	(title_block
		(title "timecard-beta-v1 — TimeCard-DC-V1.PcbDoc")
		(comment 1 "Time Appliance Project (Time Card) / footprints 34-49 of 120")
	)
	(layers
		(0 "F.Cu" signal "TOP")
		(4 "In1.Cu" signal "SGND")
		(6 "In2.Cu" signal "IN1")
		(8 "In3.Cu" signal "IN2")
		(10 "In4.Cu" signal "SGND1")
		(2 "B.Cu" signal "BOTTOM")
		(9 "F.Adhes" user "F.Adhesive")
		(11 "B.Adhes" user "B.Adhesive")
		(13 "F.Paste" user "Top Paste")
		(15 "B.Paste" user "Bottom Paste")
		(5 "F.SilkS" user "Top Overlay")
		(7 "B.SilkS" user "Bottom Overlay")
		(1 "F.Mask" user "Top Solder")
		(3 "B.Mask" user "Bottom Solder")
		(17 "Dwgs.User" user "User.Drawings")
		(19 "Cmts.User" user "User.Comments")
		(21 "Eco1.User" user "User.Eco1")
		(23 "Eco2.User" user "User.Eco2")
		(25 "Edge.Cuts" user)
		(27 "Margin" user)
		(31 "F.CrtYd" user "Top Courtyard")
		(29 "B.CrtYd" user "Bottom Courtyard")
		(35 "F.Fab" user "Top Component Center")
		(33 "B.Fab" user "Bottom Component Center")
	)
	(footprint "Passives:DIOM1608X06N"
		(layer "F.Cu")
		(at 85.112255 53.2366 90)
		(property "Reference" "D13"
			(at -1.55529 -1.375795 90)
			(unlocked yes)
			(layer "F.SilkS")
			(effects
				(font
					(size 0.762 0.762)
					(thickness 0.2286)
				)
				(justify left bottom)
			)
		)
		(property "Value" "RED"
			(at -4.13639 -0.5715 0)
			(unlocked yes)
			(layer "F.SilkS")
			(hide yes)
			(effects
				(font
					(size 1.524 1.524)
					(thickness 0.254)
				)
				(justify left bottom)
			)
		)
		(sheetname "USER_IO")
		(sheetfile "USER_IO.kicad_sch")
		(duplicate_pad_numbers_are_jumpers no)
		(fp_circle
			(center -1.275 -0.725)
			(end -1.225 -0.725)
			(stroke
				(width 0.1)
				(type solid)
			)
			(fill no)
			(layer "F.SilkS")
		)
		(pad "1" smd rect
			(at -0.725 0 180)
			(size 0.85 1)
			(layers "F.Cu" "F.Mask" "F.Paste")
			(net "NetD13_1")
		)
		(pad "2" smd rect
			(at 0.725 0 180)
			(size 0.85 1)
			(layers "F.Cu" "F.Mask" "F.Paste")
			(net "+3.3V")
		)
	)
	(footprint "Resistors:RESC1608X50N"
		(layer "F.Cu")
		(at 216.853595 105.8146 -90)
		(property "Reference" "R3"
			(at 2.864 -0.428345 90)
			(unlocked yes)
			(layer "F.SilkS")
			(effects
				(font
					(size 0.762 0.762)
					(thickness 0.2286)
				)
				(justify left bottom)
			)
		)
		(property "Value" "ERJ-3EKF4702V"
			(at -18.92681 -16.2687 0)
			(unlocked yes)
			(layer "F.SilkS")
			(hide yes)
			(effects
				(font
					(size 1.524 1.524)
					(thickness 0.254)
				)
				(justify left bottom)
			)
		)
		(sheetname "POWER")
		(sheetfile "POWER.kicad_sch")
		(duplicate_pad_numbers_are_jumpers no)
		(fp_line
			(start 0 0.5)
			(end 0 -0.5)
			(stroke
				(width 0.1524)
				(type solid)
			)
			(layer "F.SilkS")
		)
		(pad "1" smd rect
			(at -0.69 0)
			(size 1 0.72)
			(layers "F.Cu" "F.Mask" "F.Paste")
			(net "NetR3_1")
		)
		(pad "2" smd rect
			(at 0.69 0)
			(size 1 0.72)
			(layers "F.Cu" "F.Mask" "F.Paste")
			(net "+12V")
		)
	)
	(footprint "Connectors:AMPHENOL-901-143-6RFX"
		(layer "F.Cu")
		(at 63.564595 97.5596 180)
		(property "Reference" "AN1"
			(at 4.076 -6.362345 0)
			(unlocked yes)
			(layer "F.SilkS")
			(effects
				(font
					(size 0.762 0.762)
					(thickness 0.2286)
				)
				(justify left bottom)
			)
		)
		(property "Value" "901-143-6RFX"
			(at 4.6101 -12.21359 0)
			(unlocked yes)
			(layer "F.SilkS")
			(hide yes)
			(effects
				(font
					(size 1.524 1.524)
					(thickness 0.254)
				)
				(justify left bottom)
			)
		)
		(sheetname "USER_IO")
		(sheetfile "USER_IO.kicad_sch")
		(duplicate_pad_numbers_are_jumpers no)
		(fp_line
			(start 4.318 3.556)
			(end 3.302 4.572)
			(stroke
				(width 0.1778)
				(type solid)
			)
			(layer "F.SilkS")
		)
		(fp_line
			(start 4.318 -3.556)
			(end 3.302 -4.572)
			(stroke
				(width 0.1778)
				(type solid)
			)
			(layer "F.SilkS")
		)
		(fp_line
			(start 3.302 4.572)
			(end 2.54 4.572)
			(stroke
				(width 0.1778)
				(type solid)
			)
			(layer "F.SilkS")
		)
		(fp_line
			(start 3.302 -4.572)
			(end 2.54 -4.572)
			(stroke
				(width 0.1778)
				(type solid)
			)
			(layer "F.SilkS")
		)
		(fp_line
			(start 2.54 4.572)
			(end -4.572 4.572)
			(stroke
				(width 0.1778)
				(type solid)
			)
			(layer "F.SilkS")
		)
		(fp_line
			(start 2.54 -4.572)
			(end -4.572 -4.572)
			(stroke
				(width 0.1778)
				(type solid)
			)
			(layer "F.SilkS")
		)
		(fp_line
			(start -4.572 2.54)
			(end -4.572 4.572)
			(stroke
				(width 0.1778)
				(type solid)
			)
			(layer "F.SilkS")
		)
		(fp_line
			(start -4.572 -4.572)
			(end -4.572 -2.54)
			(stroke
				(width 0.1778)
				(type solid)
			)
			(layer "F.SilkS")
		)
		(pad "1" thru_hole circle
			(at 0 0 180)
			(size 2.8448 2.8448)
			(drill 1.524)
			(layers "*.Cu" "*.Mask")
			(remove_unused_layers no)
			(net "NetAN1_1")
			(thermal_bridge_angle 90)
		)
		(pad "2" thru_hole circle
			(at -2.54 2.54 180)
			(size 3.048 3.048)
			(drill 1.7272)
			(layers "*.Cu" "*.Mask")
			(remove_unused_layers no)
			(net "GND")
			(thermal_bridge_angle 90)
		)
		(pad "3" thru_hole circle
			(at -2.54 -2.54 180)
			(size 3.048 3.048)
			(drill 1.7272)
			(layers "*.Cu" "*.Mask")
			(remove_unused_layers no)
			(net "GND")
			(thermal_bridge_angle 90)
		)
		(pad "4" thru_hole circle
			(at 2.54 -2.54 180)
			(size 3.048 3.048)
			(drill 1.7272)
			(layers "*.Cu" "*.Mask")
			(remove_unused_layers no)
			(net "GND")
			(thermal_bridge_angle 90)
		)
		(pad "5" thru_hole circle
			(at 2.54 2.54 180)
			(size 3.048 3.048)
			(drill 1.7272)
			(layers "*.Cu" "*.Mask")
			(remove_unused_layers no)
			(net "GND")
			(thermal_bridge_angle 90)
		)
	)
	(footprint "Vault:CAPC1608X87X45ML20T05"
		(layer "F.Cu")
		(at 227.648595 118.1336)
		(property "Reference" "C16"
			(at 1.74 0.638345 0)
			(unlocked yes)
			(layer "F.SilkS")
			(effects
				(font
					(size 0.762 0.762)
					(thickness 0.2286)
				)
				(justify left bottom)
			)
		)
		(property "Value" "0.1uF"
			(at 0.3429 7.15899 0)
			(unlocked yes)
			(layer "F.SilkS")
			(hide yes)
			(effects
				(font
					(size 1.524 1.524)
					(thickness 0.254)
				)
				(justify left bottom)
			)
		)
		(sheetname "POWER")
		(sheetfile "POWER.kicad_sch")
		(duplicate_pad_numbers_are_jumpers no)
		(pad "1" smd rect
			(at -0.7 0 90)
			(size 1.1 1.05)
			(layers "F.Cu" "F.Mask" "F.Paste")
			(net "GND")
		)
		(pad "2" smd rect
			(at 0.7 0 90)
			(size 1.1 1.05)
			(layers "F.Cu" "F.Mask" "F.Paste")
			(net "+5.0V")
		)
	)
	(footprint "Resistors:RESC1608X50N"
		(layer "F.Cu")
		(at 214.008795 98.0676 90)
		(property "Reference" "R5"
			(at 1.639 0.398145 90)
			(unlocked yes)
			(layer "F.SilkS")
			(effects
				(font
					(size 0.762 0.762)
					(thickness 0.2286)
				)
				(justify left bottom)
			)
		)
		(property "Value" "ERJ-3EKF2612V"
			(at -3.17119 -1.0033 0)
			(unlocked yes)
			(layer "F.SilkS")
			(hide yes)
			(effects
				(font
					(size 1.524 1.524)
					(thickness 0.254)
				)
				(justify left bottom)
			)
		)
		(sheetname "POWER")
		(sheetfile "POWER.kicad_sch")
		(duplicate_pad_numbers_are_jumpers no)
		(fp_line
			(start 0 -0.5)
			(end 0 0.5)
			(stroke
				(width 0.1524)
				(type solid)
			)
			(layer "F.SilkS")
		)
		(pad "1" smd rect
			(at -0.69 0 180)
			(size 1 0.72)
			(layers "F.Cu" "F.Mask" "F.Paste")
			(net "NetR5_1")
		)
		(pad "2" smd rect
			(at 0.69 0 180)
			(size 1 0.72)
			(layers "F.Cu" "F.Mask" "F.Paste")
			(net "+3.3V")
		)
	)
	(footprint "Resistors:RESC2012X50N"
		(layer "F.Cu")
		(at 99.488595 65.3286 90)
		(property "Reference" "R18"
			(at -1.25 -3.906655 90)
			(unlocked yes)
			(layer "F.SilkS")
			(effects
				(font
					(size 0.762 0.762)
					(thickness 0.2286)
				)
				(justify left bottom)
			)
		)
		(property "Value" "CRCW080533R0FKEA"
			(at -3.52679 -1.5875 0)
			(unlocked yes)
			(layer "F.SilkS")
			(hide yes)
			(effects
				(font
					(size 1.524 1.524)
					(thickness 0.254)
				)
				(justify left bottom)
			)
		)
		(sheetname "PCIe_JTAG")
		(sheetfile "PCIe_JTAG.kicad_sch")
		(duplicate_pad_numbers_are_jumpers no)
		(fp_line
			(start 0 -0.762)
			(end 0 0.762)
			(stroke
				(width 0.1524)
				(type solid)
			)
			(layer "F.SilkS")
		)
		(pad "1" smd rect
			(at -1 0 180)
			(size 1.45 0.95)
			(layers "F.Cu" "F.Mask" "F.Paste")
			(net "FPGA_TCK")
		)
		(pad "2" smd rect
			(at 1 0 180)
			(size 1.45 0.95)
			(layers "F.Cu" "F.Mask" "F.Paste")
			(net "NetR18_2")
		)
	)
	(footprint "Capacitors:CAPC2012X14N"
		(layer "F.Cu")
		(at 227.648595 106.4496 90)
		(property "Reference" "C6"
			(at 2.046 0.483345 90)
			(unlocked yes)
			(layer "F.SilkS")
			(effects
				(font
					(size 0.762 0.762)
					(thickness 0.2286)
				)
				(justify left bottom)
			)
		)
		(property "Value" "CAP_0805_10UF_25V"
			(at -3.39979 -5.0165 0)
			(unlocked yes)
			(layer "F.SilkS")
			(hide yes)
			(effects
				(font
					(size 1.524 1.524)
					(thickness 0.254)
				)
				(justify left bottom)
			)
		)
		(sheetname "POWER")
		(sheetfile "POWER.kicad_sch")
		(duplicate_pad_numbers_are_jumpers no)
		(fp_line
			(start -0.762 -0.9652)
			(end 0.762 -0.9652)
			(stroke
				(width 0.1524)
				(type solid)
			)
			(layer "F.SilkS")
		)
		(fp_line
			(start -0.762 0.9652)
			(end 0.762 0.9652)
			(stroke
				(width 0.1524)
				(type solid)
			)
			(layer "F.SilkS")
		)
		(pad "1" smd rect
			(at -0.9 0 180)
			(size 1.45 1.15)
			(layers "F.Cu" "F.Mask" "F.Paste")
			(net "+12V")
		)
		(pad "2" smd rect
			(at 0.9 0 180)
			(size 1.45 1.15)
			(layers "F.Cu" "F.Mask" "F.Paste")
			(net "GND")
		)
	)
	(footprint "Vault:CAPC1608X87X45ML20T05"
		(layer "F.Cu")
		(at 185.488595 87.8286 -90)
		(property "Reference" "C24"
			(at 2.7714 -0.026931 90)
			(unlocked yes)
			(layer "F.SilkS")
			(effects
				(font
					(size 0.762 0.762)
					(thickness 0.2286)
				)
			)
		)
		(property "Value" "0.1uF"
			(at 2.09443 2.657602 270)
			(unlocked yes)
			(layer "F.SilkS")
			(hide yes)
			(effects
				(font
					(size 1.524 1.524)
					(thickness 0.254)
				)
			)
		)
		(sheetname "MAC")
		(sheetfile "MAC.kicad_sch")
		(duplicate_pad_numbers_are_jumpers no)
		(pad "1" smd rect
			(at -0.7 0)
			(size 1.1 1.05)
			(layers "F.Cu" "F.Mask" "F.Paste")
			(net "+3.3V")
		)
		(pad "2" smd rect
			(at 0.7 0)
			(size 1.1 1.05)
			(layers "F.Cu" "F.Mask" "F.Paste")
			(net "GND")
		)
	)
	(footprint "Vault:RESC1608X55X30NL15T15"
		(layer "F.Cu")
		(at 79.988595 56.9786 90)
		(property "Reference" "R28"
			(at -1.2 -1.206655 90)
			(unlocked yes)
			(layer "F.SilkS")
			(effects
				(font
					(size 0.762 0.762)
					(thickness 0.2286)
				)
				(justify left bottom)
			)
		)
		(property "Value" "200 OHM"
			(at -3.72999 -0.4445 0)
			(unlocked yes)
			(layer "F.SilkS")
			(hide yes)
			(effects
				(font
					(size 1.524 1.524)
					(thickness 0.254)
				)
				(justify left bottom)
			)
		)
		(sheetname "USER_IO")
		(sheetfile "USER_IO.kicad_sch")
		(duplicate_pad_numbers_are_jumpers no)
		(pad "1" smd rect
			(at -0.675 0 180)
			(size 0.95 0.8)
			(layers "F.Cu" "F.Mask" "F.Paste")
			(net "LED2")
		)
		(pad "2" smd rect
			(at 0.675 0 180)
			(size 0.95 0.8)
			(layers "F.Cu" "F.Mask" "F.Paste")
			(net "NetD12_1")
		)
	)
	(footprint "Capacitors:CAPC2012X14N"
		(layer "F.Cu")
		(at 227.775595 124.4836 180)
		(property "Reference" "C13"
			(at -1.94991 -0.690055 0)
			(unlocked yes)
			(layer "F.SilkS")
			(effects
				(font
					(size 0.762 0.762)
					(thickness 0.2286)
				)
				(justify left bottom)
			)
		)
		(property "Value" "CAP_0805_10UF_25V"
			(at 7.4295 -0.98679 0)
			(unlocked yes)
			(layer "F.SilkS")
			(hide yes)
			(effects
				(font
					(size 1.524 1.524)
					(thickness 0.254)
				)
				(justify left bottom)
			)
		)
		(sheetname "POWER")
		(sheetfile "POWER.kicad_sch")
		(duplicate_pad_numbers_are_jumpers no)
		(fp_line
			(start 0.762 0.9652)
			(end -0.762 0.9652)
			(stroke
				(width 0.1524)
				(type solid)
			)
			(layer "F.SilkS")
		)
		(fp_line
			(start 0.762 -0.9652)
			(end -0.762 -0.9652)
			(stroke
				(width 0.1524)
				(type solid)
			)
			(layer "F.SilkS")
		)
		(pad "1" smd rect
			(at -0.9 0 270)
			(size 1.45 1.15)
			(layers "F.Cu" "F.Mask" "F.Paste")
			(net "+5.0V")
		)
		(pad "2" smd rect
			(at 0.9 0 270)
			(size 1.45 1.15)
			(layers "F.Cu" "F.Mask" "F.Paste")
			(net "GND")
		)
	)
	(footprint "Resistors:RESC1608X50N"
		(layer "F.Cu")
		(at 214.188595 88.5786 90)
		(property "Reference" "R1"
			(at 2.4 0.393345 90)
			(unlocked yes)
			(layer "F.SilkS")
			(effects
				(font
					(size 0.762 0.762)
					(thickness 0.2286)
				)
				(justify left bottom)
			)
		)
		(property "Value" "ERJ-3EKF2000V"
			(at -3.17119 -1.0033 0)
			(unlocked yes)
			(layer "F.SilkS")
			(hide yes)
			(effects
				(font
					(size 1.524 1.524)
					(thickness 0.254)
				)
				(justify left bottom)
			)
		)
		(sheetname "POWER")
		(sheetfile "POWER.kicad_sch")
		(duplicate_pad_numbers_are_jumpers no)
		(fp_line
			(start 0 -0.5)
			(end 0 0.5)
			(stroke
				(width 0.1524)
				(type solid)
			)
			(layer "F.SilkS")
		)
		(pad "1" smd rect
			(at -0.69 0 180)
			(size 1 0.72)
			(layers "F.Cu" "F.Mask" "F.Paste")
			(net "GND")
		)
		(pad "2" smd rect
			(at 0.69 0 180)
			(size 1 0.72)
			(layers "F.Cu" "F.Mask" "F.Paste")
			(net "NetD4_1")
		)
	)
	(footprint "Resistors:RESC1005X04N"
		(layer "F.Cu")
		(at 122.088595 145.5786 -90)
		(property "Reference" "R23"
			(at 1.27491 0.808535 90)
			(unlocked yes)
			(layer "F.SilkS")
			(effects
				(font
					(size 0.762 0.762)
					(thickness 0.2286)
				)
				(justify left bottom)
			)
		)
		(property "Value" "ERJ-2GE0R00X"
			(at 3.42519 0.2413 0)
			(unlocked yes)
			(layer "F.SilkS")
			(hide yes)
			(effects
				(font
					(size 1.524 1.524)
					(thickness 0.254)
				)
				(justify left bottom)
			)
		)
		(sheetname "PCIe_JTAG")
		(sheetfile "PCIe_JTAG.kicad_sch")
		(duplicate_pad_numbers_are_jumpers no)
		(pad "1" smd rect
			(at -0.425 0)
			(size 0.6 0.65)
			(layers "F.Cu" "F.Mask" "F.Paste")
			(net "PRSNT")
		)
		(pad "2" smd rect
			(at 0.425 0)
			(size 0.6 0.65)
			(layers "F.Cu" "F.Mask" "F.Paste")
			(net "NetP2_B17")
		)
	)
	(footprint "Passives:IND_PM124SH"
		(layer "F.Cu")
		(at 228.156595 94.2576 -90)
		(property "Reference" "L2"
			(at -7.488745 -4.73741 0)
			(unlocked yes)
			(layer "F.SilkS")
			(effects
				(font
					(size 0.762 0.762)
					(thickness 0.2286)
				)
				(justify left bottom)
			)
		)
		(property "Value" "PM124SH-100M-RC"
			(at 11.14679 12.7381 0)
			(unlocked yes)
			(layer "F.SilkS")
			(hide yes)
			(effects
				(font
					(size 1.524 1.524)
					(thickness 0.254)
				)
				(justify left bottom)
			)
		)
		(sheetname "POWER")
		(sheetfile "POWER.kicad_sch")
		(duplicate_pad_numbers_are_jumpers no)
		(fp_line
			(start -6.681 6.4)
			(end -6.681 -6.4)
			(stroke
				(width 0.254)
				(type solid)
			)
			(layer "F.SilkS")
		)
		(fp_line
			(start 6.681 6.4)
			(end -6.681 6.4)
			(stroke
				(width 0.254)
				(type solid)
			)
			(layer "F.SilkS")
		)
		(fp_line
			(start 6.681 6.4)
			(end 6.681 -6.4)
			(stroke
				(width 0.254)
				(type solid)
			)
			(layer "F.SilkS")
		)
		(fp_line
			(start 6.681 -6.4)
			(end -6.681 -6.4)
			(stroke
				(width 0.254)
				(type solid)
			)
			(layer "F.SilkS")
		)
		(pad "1" smd rect
			(at -4.85 0 270)
			(size 2.9 5.4)
			(layers "F.Cu" "F.Mask" "F.Paste")
			(net "+3.3V")
		)
		(pad "2" smd rect
			(at 4.85 0 270)
			(size 2.9 5.4)
			(layers "F.Cu" "F.Mask" "F.Paste")
			(net "NetC3_2")
		)
	)
	(footprint "Resistors:RESC1608X50N"
		(layer "F.Cu")
		(at 219.488595 98.0786 180)
		(property "Reference" "R7"
			(at 3.982 -0.350345 0)
			(unlocked yes)
			(layer "F.SilkS")
			(effects
				(font
					(size 0.762 0.762)
					(thickness 0.2286)
				)
				(justify left bottom)
			)
		)
		(property "Value" "ERJ-3EKF1002V"
			(at -10.9347 3.94081 0)
			(unlocked yes)
			(layer "F.SilkS")
			(hide yes)
			(effects
				(font
					(size 1.524 1.524)
					(thickness 0.254)
				)
				(justify left bottom)
			)
		)
		(sheetname "POWER")
		(sheetfile "POWER.kicad_sch")
		(duplicate_pad_numbers_are_jumpers no)
		(fp_line
			(start 0 -0.5)
			(end 0 0.5)
			(stroke
				(width 0.1524)
				(type solid)
			)
			(layer "F.SilkS")
		)
		(pad "1" smd rect
			(at -0.69 0 270)
			(size 1 0.72)
			(layers "F.Cu" "F.Mask" "F.Paste")
			(net "GND")
		)
		(pad "2" smd rect
			(at 0.69 0 270)
			(size 1 0.72)
			(layers "F.Cu" "F.Mask" "F.Paste")
			(net "NetR5_1")
		)
	)
	(footprint "Vault:SOT143-4L"
		(layer "F.Cu")
		(at 72.538595 103.9286 90)
		(property "Reference" "D2"
			(at -2.926931 1.178605 360)
			(unlocked yes)
			(layer "F.SilkS")
			(effects
				(font
					(size 0.762 0.762)
					(thickness 0.2286)
				)
			)
		)
		(property "Value" "8240136"
			(at 2.7035 3.368802 90)
			(unlocked yes)
			(layer "F.SilkS")
			(hide yes)
			(effects
				(font
					(size 1.524 1.524)
					(thickness 0.254)
				)
			)
		)
		(sheetname "USER_IO")
		(sheetfile "USER_IO.kicad_sch")
		(duplicate_pad_numbers_are_jumpers no)
		(fp_line
			(start 2.05 -1.7)
			(end 2.05 1.7)
			(stroke
				(width 0.2)
				(type solid)
			)
			(layer "F.SilkS")
		)
		(fp_line
			(start -2.05 -1.7)
			(end 2.05 -1.7)
			(stroke
				(width 0.2)
				(type solid)
			)
			(layer "F.SilkS")
		)
		(fp_line
			(start -2.05 -1.7)
			(end -2.05 1.675)
			(stroke
				(width 0.2)
				(type solid)
			)
			(layer "F.SilkS")
		)
		(fp_line
			(start -2.05 1.7)
			(end 2.05 1.7)
			(stroke
				(width 0.2)
				(type solid)
			)
			(layer "F.SilkS")
		)
		(fp_circle
			(center -2.404 -1.075)
			(end -2.15 -1.075)
			(stroke
				(width 0.2)
				(type solid)
			)
			(fill no)
			(layer "F.SilkS")
		)
		(pad "1" smd rect
			(at -1.1 -0.75 180)
			(size 1.4 1.4)
			(layers "F.Cu" "F.Mask" "F.Paste")
			(net "GND")
		)
		(pad "2" smd rect
			(at -1.1 0.95 180)
			(size 1 1.4)
			(layers "F.Cu" "F.Mask" "F.Paste")
			(net "NetAN2_1")
		)
		(pad "3" smd rect
			(at 1.1 0.95 180)
			(size 1 1.4)
			(layers "F.Cu" "F.Mask" "F.Paste")
			(net "NetAN1_1")
		)
		(pad "4" smd rect
			(at 1.1 -0.95 180)
			(size 1 1.4)
			(layers "F.Cu" "F.Mask" "F.Paste")
			(net "+3.3V")
		)
	)
	(footprint "Capacitors:CAPC2012X14N"
		(layer "F.Cu")
		(at 227.775595 121.6896 180)
		(property "Reference" "C14"
			(at -1.97531 -1.604455 0)
			(unlocked yes)
			(layer "F.SilkS")
			(effects
				(font
					(size 0.762 0.762)
					(thickness 0.2286)
				)
				(justify left bottom)
			)
		)
		(property "Value" "CAP_0805_10UF_25V"
			(at 4.6355 -3.78079 0)
			(unlocked yes)
			(layer "F.SilkS")
			(hide yes)
			(effects
				(font
					(size 1.524 1.524)
					(thickness 0.254)
				)
				(justify left bottom)
			)
		)
		(sheetname "POWER")
		(sheetfile "POWER.kicad_sch")
		(duplicate_pad_numbers_are_jumpers no)
		(fp_line
			(start 0.762 0.9652)
			(end -0.762 0.9652)
			(stroke
				(width 0.1524)
				(type solid)
			)
			(layer "F.SilkS")
		)
		(fp_line
			(start 0.762 -0.9652)
			(end -0.762 -0.9652)
			(stroke
				(width 0.1524)
				(type solid)
			)
			(layer "F.SilkS")
		)
		(pad "1" smd rect
			(at -0.9 0 270)
			(size 1.45 1.15)
			(layers "F.Cu" "F.Mask" "F.Paste")
			(net "+5.0V")
		)
		(pad "2" smd rect
			(at 0.9 0 270)
			(size 1.45 1.15)
			(layers "F.Cu" "F.Mask" "F.Paste")
			(net "GND")
		)
	)
)
